(kicad_pcb
	(version 20260206)
	(generator "pcbnew")
	(generator_version "10.0")
	(general
		(thickness 1.6)
		(legacy_teardrops no)
	)
	(paper "A4")
	(title_block
		(title "04192023_DAF0TMB3IC0_F0TG_MB_C_brd_V02_OCP.brd")
		(comment 1 "Grand Teton / footprints 6354-6359 of 8354")
	)
	(layers
		(0 "F.Cu" signal "TOP")
		(4 "In1.Cu" signal "GND")
		(6 "In2.Cu" signal "IN1")
		(8 "In3.Cu" signal "GND1")
		(10 "In4.Cu" signal "IN2")
		(12 "In5.Cu" signal "GND2")
		(14 "In6.Cu" signal "IN3")
		(16 "In7.Cu" signal "GND3")
		(18 "In8.Cu" signal "VCC")
		(20 "In9.Cu" signal "VCC1")
		(22 "In10.Cu" signal "GND4")
		(24 "In11.Cu" signal "IN4")
		(26 "In12.Cu" signal "GND5")
		(28 "In13.Cu" signal "IN5")
		(30 "In14.Cu" signal "GND6")
		(32 "In15.Cu" signal "IN6")
		(34 "In16.Cu" signal "GND7")
		(2 "B.Cu" signal "BOTTOM")
		(9 "F.Adhes" user "F.Adhesive")
		(11 "B.Adhes" user "B.Adhesive")
		(13 "F.Paste" user "Package Geometry/Pastemask Top")
		(15 "B.Paste" user "Package Geometry/Pastemask Bottom")
		(5 "F.SilkS" user "Ref Des/Silkscreen Top")
		(7 "B.SilkS" user "Ref Des/Silkscreen Bottom")
		(1 "F.Mask" user "Board Geometry/Soldermask Top")
		(3 "B.Mask" user "Board Geometry/Soldermask Bottom")
		(17 "Dwgs.User" user "User.Drawings")
		(19 "Cmts.User" user "User.Comments")
		(21 "Eco1.User" user "User.Eco1")
		(23 "Eco2.User" user "User.Eco2")
		(25 "Edge.Cuts" user "Board Geometry/Outline")
		(27 "Margin" user)
		(31 "F.CrtYd" user "Package Geometry/Place Bound Top")
		(29 "B.CrtYd" user "Package Geometry/Place Bound Bottom")
		(35 "F.Fab" user "Ref Des/Assembly Top")
		(33 "B.Fab" user "Ref Des/Assembly Bottom")
	)
	(footprint ""
		(layer "B.Cu")
		(at 384.739388 -180.078634 90)
		(property "Reference" "PR350"
			(at 0 0 90)
			(layer "B.SilkS")
			(hide yes)
			(effects
				(font
					(size 1.27 1.27)
				)
				(justify mirror)
			)
		)
		(property "Value" ""
			(at 0 0 90)
			(layer "B.Fab")
			(effects
				(font
					(size 1.27 1.27)
				)
				(justify mirror)
			)
		)
		(duplicate_pad_numbers_are_jumpers no)
		(fp_line
			(start 0.7874 -0.4064)
			(end -0.7874 -0.4064)
			(stroke
				(width 0.1524)
				(type default)
			)
			(layer "B.SilkS")
		)
		(fp_line
			(start -0.7874 -0.4064)
			(end -0.7874 0.4064)
			(stroke
				(width 0.1524)
				(type default)
			)
			(layer "B.SilkS")
		)
		(fp_line
			(start 0.7874 0.4064)
			(end 0.7874 -0.4064)
			(stroke
				(width 0.1524)
				(type default)
			)
			(layer "B.SilkS")
		)
		(fp_line
			(start -0.7874 0.4064)
			(end 0.7874 0.4064)
			(stroke
				(width 0.1524)
				(type default)
			)
			(layer "B.SilkS")
		)
		(fp_line
			(start 0.67945 -0.305054)
			(end 0.12065 -0.305054)
			(stroke
				(width 0.1)
				(type default)
			)
			(layer "B.Fab")
		)
		(fp_line
			(start 0.12065 -0.305054)
			(end 0.12065 -0.2794)
			(stroke
				(width 0.1)
				(type default)
			)
			(layer "B.Fab")
		)
		(fp_line
			(start -0.12065 -0.3048)
			(end -0.67945 -0.3048)
			(stroke
				(width 0.1)
				(type default)
			)
			(layer "B.Fab")
		)
		(fp_line
			(start -0.67945 -0.3048)
			(end -0.67945 0.3048)
			(stroke
				(width 0.1)
				(type default)
			)
			(layer "B.Fab")
		)
		(fp_line
			(start 0.12065 -0.2794)
			(end -0.12065 -0.2794)
			(stroke
				(width 0.1)
				(type default)
			)
			(layer "B.Fab")
		)
		(fp_line
			(start -0.12065 -0.2794)
			(end -0.12065 -0.3048)
			(stroke
				(width 0.1)
				(type default)
			)
			(layer "B.Fab")
		)
		(fp_line
			(start 0.12065 0.2794)
			(end 0.12065 0.3048)
			(stroke
				(width 0.1)
				(type default)
			)
			(layer "B.Fab")
		)
		(fp_line
			(start -0.120396 0.2794)
			(end 0.12065 0.2794)
			(stroke
				(width 0.1)
				(type default)
			)
			(layer "B.Fab")
		)
		(fp_line
			(start 0.67945 0.3048)
			(end 0.67945 -0.305054)
			(stroke
				(width 0.1)
				(type default)
			)
			(layer "B.Fab")
		)
		(fp_line
			(start 0.12065 0.3048)
			(end 0.67945 0.3048)
			(stroke
				(width 0.1)
				(type default)
			)
			(layer "B.Fab")
		)
		(fp_line
			(start -0.120396 0.3048)
			(end -0.120396 0.2794)
			(stroke
				(width 0.1)
				(type default)
			)
			(layer "B.Fab")
		)
		(fp_line
			(start -0.67945 0.3048)
			(end -0.120396 0.3048)
			(stroke
				(width 0.1)
				(type default)
			)
			(layer "B.Fab")
		)
		(pad "1" smd circle
			(at 0.40005 0 270)
			(size 0 0)
			(layers "B.Cu" "B.Mask" "B.Paste")
			(net "PVDDCR_CPU0_P0_VOS3")
		)
		(pad "2" smd circle
			(at -0.40005 0 270)
			(size 0 0)
			(layers "B.Cu" "B.Mask" "B.Paste")
			(net "PVDDCR_CPU0_P0")
		)
	)
	(footprint ""
		(layer "B.Cu")
		(at 350.495362 -389.49503)
		(property "Reference" "C7012"
			(at 2.35966 3.083052 0)
			(unlocked yes)
			(layer "B.SilkS")
			(effects
				(font
					(size 0.7874 0.5842)
					(thickness 0.1524)
				)
				(justify left mirror)
			)
		)
		(property "Value" ""
			(at 0 0 0)
			(layer "B.Fab")
			(effects
				(font
					(size 1.27 1.27)
				)
				(justify mirror)
			)
		)
		(duplicate_pad_numbers_are_jumpers no)
		(fp_line
			(start -4.53898 -2.15011)
			(end -4.53898 2.15011)
			(stroke
				(width 0.1524)
				(type default)
			)
			(layer "B.SilkS")
		)
		(fp_line
			(start -4.53898 2.15011)
			(end 4.53898 2.15011)
			(stroke
				(width 0.1524)
				(type default)
			)
			(layer "B.SilkS")
		)
		(fp_line
			(start 4.53898 -2.150618)
			(end 4.539742 2.152142)
			(stroke
				(width 0.1524)
				(type default)
			)
			(layer "B.SilkS")
		)
		(fp_line
			(start 4.53898 -2.15011)
			(end -4.53898 -2.15011)
			(stroke
				(width 0.1524)
				(type default)
			)
			(layer "B.SilkS")
		)
		(fp_line
			(start 4.53898 2.15011)
			(end 4.53898 -2.15011)
			(stroke
				(width 0.1524)
				(type default)
			)
			(layer "B.SilkS")
		)
		(fp_line
			(start 4.69138 -2.150618)
			(end 4.692396 2.161032)
			(stroke
				(width 0.1524)
				(type default)
			)
			(layer "B.SilkS")
		)
		(fp_line
			(start 4.83108 2.150364)
			(end 4.447794 2.149348)
			(stroke
				(width 0.1524)
				(type default)
			)
			(layer "B.SilkS")
		)
		(fp_line
			(start 4.84378 -2.150618)
			(end 4.53898 -2.150618)
			(stroke
				(width 0.1524)
				(type default)
			)
			(layer "B.SilkS")
		)
		(fp_line
			(start 4.84378 -2.150618)
			(end 4.842256 2.163064)
			(stroke
				(width 0.1524)
				(type default)
			)
			(layer "B.SilkS")
		)
		(fp_line
			(start -3.64998 -2.15011)
			(end -3.64998 2.15011)
			(stroke
				(width 0.1)
				(type default)
			)
			(layer "B.Fab")
		)
		(fp_line
			(start -3.64998 2.15011)
			(end 3.64998 2.15011)
			(stroke
				(width 0.1)
				(type default)
			)
			(layer "B.Fab")
		)
		(fp_line
			(start 3.64998 -2.15011)
			(end -3.64998 -2.15011)
			(stroke
				(width 0.1)
				(type default)
			)
			(layer "B.Fab")
		)
		(fp_line
			(start 3.64998 2.15011)
			(end 3.64998 -2.15011)
			(stroke
				(width 0.1)
				(type default)
			)
			(layer "B.Fab")
		)
		(fp_text user "-"
			(at -2.872994 2.336292 0)
			(unlocked yes)
			(layer "B.SilkS")
			(effects
				(font
					(size 1.905 1.4224)
					(thickness 0.1524)
				)
				(justify left mirror)
			)
		)
		(fp_text user "+"
			(at 6.214872 -0.337058 0)
			(unlocked yes)
			(layer "B.SilkS")
			(effects
				(font
					(size 1.905 1.4224)
					(thickness 0.1524)
				)
				(justify left mirror)
			)
		)
		(fp_text user "-"
			(at -4.313174 -0.094488 0)
			(unlocked yes)
			(layer "B.Fab")
			(effects
				(font
					(size 1.905 1.4224)
					(thickness 0.1524)
				)
				(justify left mirror)
			)
		)
		(fp_text user "+"
			(at 6.214872 -0.337058 0)
			(unlocked yes)
			(layer "B.Fab")
			(effects
				(font
					(size 1.905 1.4224)
					(thickness 0.1524)
				)
				(justify left mirror)
			)
		)
		(pad "1" smd rect
			(at 3.199892 0 180)
			(size 2.413 2.8194)
			(layers "B.Cu" "B.Mask" "B.Paste")
			(net "P0V9_CPU0_RT1_2A")
		)
		(pad "2" smd rect
			(at -3.199892 0 180)
			(size 2.413 2.8194)
			(layers "B.Cu" "B.Mask" "B.Paste")
			(net "GND")
		)
	)
	(footprint ""
		(layer "B.Cu")
		(at 401.554696 -344.850212 90)
		(property "Reference" "C226"
			(at 0 0 90)
			(layer "B.SilkS")
			(hide yes)
			(effects
				(font
					(size 1.27 1.27)
				)
				(justify mirror)
			)
		)
		(property "Value" ""
			(at 0 0 90)
			(layer "B.Fab")
			(effects
				(font
					(size 1.27 1.27)
				)
				(justify mirror)
			)
		)
		(duplicate_pad_numbers_are_jumpers no)
		(fp_line
			(start 0.7874 -0.4064)
			(end -0.7874 -0.4064)
			(stroke
				(width 0.1524)
				(type default)
			)
			(layer "B.SilkS")
		)
		(fp_line
			(start -0.7874 -0.4064)
			(end -0.7874 0.4064)
			(stroke
				(width 0.1524)
				(type default)
			)
			(layer "B.SilkS")
		)
		(fp_line
			(start 0.7874 0.4064)
			(end 0.7874 -0.4064)
			(stroke
				(width 0.1524)
				(type default)
			)
			(layer "B.SilkS")
		)
		(fp_line
			(start -0.7874 0.4064)
			(end 0.7874 0.4064)
			(stroke
				(width 0.1524)
				(type default)
			)
			(layer "B.SilkS")
		)
		(fp_line
			(start 0.67945 -0.305054)
			(end 0.12065 -0.305054)
			(stroke
				(width 0.1)
				(type default)
			)
			(layer "B.Fab")
		)
		(fp_line
			(start 0.12065 -0.305054)
			(end 0.12065 -0.2794)
			(stroke
				(width 0.1)
				(type default)
			)
			(layer "B.Fab")
		)
		(fp_line
			(start -0.12065 -0.3048)
			(end -0.67945 -0.3048)
			(stroke
				(width 0.1)
				(type default)
			)
			(layer "B.Fab")
		)
		(fp_line
			(start -0.67945 -0.3048)
			(end -0.67945 0.3048)
			(stroke
				(width 0.1)
				(type default)
			)
			(layer "B.Fab")
		)
		(fp_line
			(start 0.12065 -0.2794)
			(end -0.12065 -0.2794)
			(stroke
				(width 0.1)
				(type default)
			)
			(layer "B.Fab")
		)
		(fp_line
			(start -0.12065 -0.2794)
			(end -0.12065 -0.3048)
			(stroke
				(width 0.1)
				(type default)
			)
			(layer "B.Fab")
		)
		(fp_line
			(start 0.12065 0.2794)
			(end 0.12065 0.3048)
			(stroke
				(width 0.1)
				(type default)
			)
			(layer "B.Fab")
		)
		(fp_line
			(start -0.120396 0.2794)
			(end 0.12065 0.2794)
			(stroke
				(width 0.1)
				(type default)
			)
			(layer "B.Fab")
		)
		(fp_line
			(start 0.67945 0.3048)
			(end 0.67945 -0.305054)
			(stroke
				(width 0.1)
				(type default)
			)
			(layer "B.Fab")
		)
		(fp_line
			(start 0.12065 0.3048)
			(end 0.67945 0.3048)
			(stroke
				(width 0.1)
				(type default)
			)
			(layer "B.Fab")
		)
		(fp_line
			(start -0.120396 0.3048)
			(end -0.120396 0.2794)
			(stroke
				(width 0.1)
				(type default)
			)
			(layer "B.Fab")
		)
		(fp_line
			(start -0.67945 0.3048)
			(end -0.120396 0.3048)
			(stroke
				(width 0.1)
				(type default)
			)
			(layer "B.Fab")
		)
		(pad "1" smd circle
			(at 0.40005 0 270)
			(size 0 0)
			(layers "B.Cu" "B.Mask" "B.Paste")
			(net "PVDD18_S5_P0")
		)
		(pad "2" smd circle
			(at -0.40005 0 270)
			(size 0 0)
			(layers "B.Cu" "B.Mask" "B.Paste")
			(net "GND")
		)
	)
	(footprint ""
		(layer "B.Cu")
		(at 90.209878 -142.85341)
		(property "Reference" "C249"
			(at 0 0 0)
			(layer "B.SilkS")
			(hide yes)
			(effects
				(font
					(size 1.27 1.27)
				)
				(justify mirror)
			)
		)
		(property "Value" ""
			(at 0 0 0)
			(layer "B.Fab")
			(effects
				(font
					(size 1.27 1.27)
				)
				(justify mirror)
			)
		)
		(duplicate_pad_numbers_are_jumpers no)
		(fp_line
			(start -0.7874 -0.4064)
			(end -0.7874 0.4064)
			(stroke
				(width 0.1524)
				(type default)
			)
			(layer "B.SilkS")
		)
		(fp_line
			(start -0.7874 0.4064)
			(end 0.7874 0.4064)
			(stroke
				(width 0.1524)
				(type default)
			)
			(layer "B.SilkS")
		)
		(fp_line
			(start 0.7874 -0.4064)
			(end -0.7874 -0.4064)
			(stroke
				(width 0.1524)
				(type default)
			)
			(layer "B.SilkS")
		)
		(fp_line
			(start 0.7874 0.4064)
			(end 0.7874 -0.4064)
			(stroke
				(width 0.1524)
				(type default)
			)
			(layer "B.SilkS")
		)
		(fp_line
			(start -0.67945 -0.3048)
			(end -0.67945 0.3048)
			(stroke
				(width 0.1)
				(type default)
			)
			(layer "B.Fab")
		)
		(fp_line
			(start -0.67945 0.3048)
			(end -0.120396 0.3048)
			(stroke
				(width 0.1)
				(type default)
			)
			(layer "B.Fab")
		)
		(fp_line
			(start -0.12065 -0.3048)
			(end -0.67945 -0.3048)
			(stroke
				(width 0.1)
				(type default)
			)
			(layer "B.Fab")
		)
		(fp_line
			(start -0.12065 -0.2794)
			(end -0.12065 -0.3048)
			(stroke
				(width 0.1)
				(type default)
			)
			(layer "B.Fab")
		)
		(fp_line
			(start -0.120396 0.2794)
			(end 0.12065 0.2794)
			(stroke
				(width 0.1)
				(type default)
			)
			(layer "B.Fab")
		)
		(fp_line
			(start -0.120396 0.3048)
			(end -0.120396 0.2794)
			(stroke
				(width 0.1)
				(type default)
			)
			(layer "B.Fab")
		)
		(fp_line
			(start 0.12065 -0.305054)
			(end 0.12065 -0.2794)
			(stroke
				(width 0.1)
				(type default)
			)
			(layer "B.Fab")
		)
		(fp_line
			(start 0.12065 -0.2794)
			(end -0.12065 -0.2794)
			(stroke
				(width 0.1)
				(type default)
			)
			(layer "B.Fab")
		)
		(fp_line
			(start 0.12065 0.2794)
			(end 0.12065 0.3048)
			(stroke
				(width 0.1)
				(type default)
			)
			(layer "B.Fab")
		)
		(fp_line
			(start 0.12065 0.3048)
			(end 0.67945 0.3048)
			(stroke
				(width 0.1)
				(type default)
			)
			(layer "B.Fab")
		)
		(fp_line
			(start 0.67945 -0.305054)
			(end 0.12065 -0.305054)
			(stroke
				(width 0.1)
				(type default)
			)
			(layer "B.Fab")
		)
		(fp_line
			(start 0.67945 0.3048)
			(end 0.67945 -0.305054)
			(stroke
				(width 0.1)
				(type default)
			)
			(layer "B.Fab")
		)
		(pad "1" smd circle
			(at 0.40005 0 180)
			(size 0 0)
			(layers "B.Cu" "B.Mask" "B.Paste")
			(net "PVDDCR_CPU0_P1_EN_R")
		)
		(pad "2" smd circle
			(at -0.40005 0 180)
			(size 0 0)
			(layers "B.Cu" "B.Mask" "B.Paste")
			(net "GND")
		)
	)
	(footprint ""
		(layer "B.Cu")
		(at 16.207994 -99.842066)
		(property "Reference" "C2038"
			(at 0 0 0)
			(layer "B.SilkS")
			(hide yes)
			(effects
				(font
					(size 1.27 1.27)
				)
				(justify mirror)
			)
		)
		(property "Value" ""
			(at 0 0 0)
			(layer "B.Fab")
			(effects
				(font
					(size 1.27 1.27)
				)
				(justify mirror)
			)
		)
		(duplicate_pad_numbers_are_jumpers no)
		(fp_line
			(start -0.7874 -0.4064)
			(end -0.7874 0.4064)
			(stroke
				(width 0.1524)
				(type default)
			)
			(layer "B.SilkS")
		)
		(fp_line
			(start -0.7874 0.4064)
			(end 0.7874 0.4064)
			(stroke
				(width 0.1524)
				(type default)
			)
			(layer "B.SilkS")
		)
		(fp_line
			(start 0.7874 -0.4064)
			(end -0.7874 -0.4064)
			(stroke
				(width 0.1524)
				(type default)
			)
			(layer "B.SilkS")
		)
		(fp_line
			(start 0.7874 0.4064)
			(end 0.7874 -0.4064)
			(stroke
				(width 0.1524)
				(type default)
			)
			(layer "B.SilkS")
		)
		(fp_line
			(start -0.67945 -0.3048)
			(end -0.67945 0.3048)
			(stroke
				(width 0.1)
				(type default)
			)
			(layer "B.Fab")
		)
		(fp_line
			(start -0.67945 0.3048)
			(end -0.120396 0.3048)
			(stroke
				(width 0.1)
				(type default)
			)
			(layer "B.Fab")
		)
		(fp_line
			(start -0.12065 -0.3048)
			(end -0.67945 -0.3048)
			(stroke
				(width 0.1)
				(type default)
			)
			(layer "B.Fab")
		)
		(fp_line
			(start -0.12065 -0.2794)
			(end -0.12065 -0.3048)
			(stroke
				(width 0.1)
				(type default)
			)
			(layer "B.Fab")
		)
		(fp_line
			(start -0.120396 0.2794)
			(end 0.12065 0.2794)
			(stroke
				(width 0.1)
				(type default)
			)
			(layer "B.Fab")
		)
		(fp_line
			(start -0.120396 0.3048)
			(end -0.120396 0.2794)
			(stroke
				(width 0.1)
				(type default)
			)
			(layer "B.Fab")
		)
		(fp_line
			(start 0.12065 -0.305054)
			(end 0.12065 -0.2794)
			(stroke
				(width 0.1)
				(type default)
			)
			(layer "B.Fab")
		)
		(fp_line
			(start 0.12065 -0.2794)
			(end -0.12065 -0.2794)
			(stroke
				(width 0.1)
				(type default)
			)
			(layer "B.Fab")
		)
		(fp_line
			(start 0.12065 0.2794)
			(end 0.12065 0.3048)
			(stroke
				(width 0.1)
				(type default)
			)
			(layer "B.Fab")
		)
		(fp_line
			(start 0.12065 0.3048)
			(end 0.67945 0.3048)
			(stroke
				(width 0.1)
				(type default)
			)
			(layer "B.Fab")
		)
		(fp_line
			(start 0.67945 -0.305054)
			(end 0.12065 -0.305054)
			(stroke
				(width 0.1)
				(type default)
			)
			(layer "B.Fab")
		)
		(fp_line
			(start 0.67945 0.3048)
			(end 0.67945 -0.305054)
			(stroke
				(width 0.1)
				(type default)
			)
			(layer "B.Fab")
		)
		(pad "1" smd circle
			(at 0.40005 0 180)
			(size 0 0)
			(layers "B.Cu" "B.Mask" "B.Paste")
			(net "P3V3_AUX_USB_HUB")
		)
		(pad "2" smd circle
			(at -0.40005 0 180)
			(size 0 0)
			(layers "B.Cu" "B.Mask" "B.Paste")
			(net "GND")
		)
	)
	(footprint ""
		(layer "B.Cu")
		(at 411.41904 -398.942052 90)
		(property "Reference" "C670"
			(at 0 0 90)
			(layer "B.SilkS")
			(hide yes)
			(effects
				(font
					(size 1.27 1.27)
				)
				(justify mirror)
			)
		)
		(property "Value" ""
			(at 0 0 90)
			(layer "B.Fab")
			(effects
				(font
					(size 1.27 1.27)
				)
				(justify mirror)
			)
		)
		(duplicate_pad_numbers_are_jumpers no)
		(fp_line
			(start 0.7874 -0.4064)
			(end -0.7874 -0.4064)
			(stroke
				(width 0.1524)
				(type default)
			)
			(layer "B.SilkS")
		)
		(fp_line
			(start -0.7874 -0.4064)
			(end -0.7874 0.4064)
			(stroke
				(width 0.1524)
				(type default)
			)
			(layer "B.SilkS")
		)
		(fp_line
			(start 0.7874 0.4064)
			(end 0.7874 -0.4064)
			(stroke
				(width 0.1524)
				(type default)
			)
			(layer "B.SilkS")
		)
		(fp_line
			(start -0.7874 0.4064)
			(end 0.7874 0.4064)
			(stroke
				(width 0.1524)
				(type default)
			)
			(layer "B.SilkS")
		)
		(fp_line
			(start 0.67945 -0.305054)
			(end 0.12065 -0.305054)
			(stroke
				(width 0.1)
				(type default)
			)
			(layer "B.Fab")
		)
		(fp_line
			(start 0.12065 -0.305054)
			(end 0.12065 -0.2794)
			(stroke
				(width 0.1)
				(type default)
			)
			(layer "B.Fab")
		)
		(fp_line
			(start -0.12065 -0.3048)
			(end -0.67945 -0.3048)
			(stroke
				(width 0.1)
				(type default)
			)
			(layer "B.Fab")
		)
		(fp_line
			(start -0.67945 -0.3048)
			(end -0.67945 0.3048)
			(stroke
				(width 0.1)
				(type default)
			)
			(layer "B.Fab")
		)
		(fp_line
			(start 0.12065 -0.2794)
			(end -0.12065 -0.2794)
			(stroke
				(width 0.1)
				(type default)
			)
			(layer "B.Fab")
		)
		(fp_line
			(start -0.12065 -0.2794)
			(end -0.12065 -0.3048)
			(stroke
				(width 0.1)
				(type default)
			)
			(layer "B.Fab")
		)
		(fp_line
			(start 0.12065 0.2794)
			(end 0.12065 0.3048)
			(stroke
				(width 0.1)
				(type default)
			)
			(layer "B.Fab")
		)
		(fp_line
			(start -0.120396 0.2794)
			(end 0.12065 0.2794)
			(stroke
				(width 0.1)
				(type default)
			)
			(layer "B.Fab")
		)
		(fp_line
			(start 0.67945 0.3048)
			(end 0.67945 -0.305054)
			(stroke
				(width 0.1)
				(type default)
			)
			(layer "B.Fab")
		)
		(fp_line
			(start 0.12065 0.3048)
			(end 0.67945 0.3048)
			(stroke
				(width 0.1)
				(type default)
			)
			(layer "B.Fab")
		)
		(fp_line
			(start -0.120396 0.3048)
			(end -0.120396 0.2794)
			(stroke
				(width 0.1)
				(type default)
			)
			(layer "B.Fab")
		)
		(fp_line
			(start -0.67945 0.3048)
			(end -0.120396 0.3048)
			(stroke
				(width 0.1)
				(type default)
			)
			(layer "B.Fab")
		)
		(pad "1" smd circle
			(at 0.40005 0 270)
			(size 0 0)
			(layers "B.Cu" "B.Mask" "B.Paste")
			(net "P1V8_CPU0_RT2_1A")
		)
		(pad "2" smd circle
			(at -0.40005 0 270)
			(size 0 0)
			(layers "B.Cu" "B.Mask" "B.Paste")
			(net "GND")
		)
	)
)
